# T6G (Grand Teton) — schematic netlist excerpt (pin names and nets, part order shuffled) for the footprints in the layout excerpt that follows; sources: Cadence DE-HDL packaged netlist, KiCad conversion of 04192023_DAF0TMB3IC0_F0TG_MB_C_brd_V02_OCP.brd

R6788  Q_RES  1K 1% CHIP  pkg 0201LF  page 322 : A = U12_E2 ; B = GND
PC2140  Q_CAP  1UF 25V 10% X6S  pkg C0402  page 140 : A = P3V3_AUX ; B = GND
R3690  Q_RES  4.7K 1% EMPTY  pkg 0402LF  page 257 : A = ADC128_VREF ; B = GND

(kicad_pcb
	(version 20260206)
	(generator "pcbnew")
	(generator_version "10.0")
	(general
		(thickness 1.6)
		(legacy_teardrops no)
	)
	(paper "A4")
	(title_block
		(title "04192023_DAF0TMB3IC0_F0TG_MB_C_brd_V02_OCP.brd")
		(comment 1 "Grand Teton / footprints 3320-3322 of 8354")
	)
	(layers
		(0 "F.Cu" signal "TOP")
		(4 "In1.Cu" signal "GND")
		(6 "In2.Cu" signal "IN1")
		(8 "In3.Cu" signal "GND1")
		(10 "In4.Cu" signal "IN2")
		(12 "In5.Cu" signal "GND2")
		(14 "In6.Cu" signal "IN3")
		(16 "In7.Cu" signal "GND3")
		(18 "In8.Cu" signal "VCC")
		(20 "In9.Cu" signal "VCC1")
		(22 "In10.Cu" signal "GND4")
		(24 "In11.Cu" signal "IN4")
		(26 "In12.Cu" signal "GND5")
		(28 "In13.Cu" signal "IN5")
		(30 "In14.Cu" signal "GND6")
		(32 "In15.Cu" signal "IN6")
		(34 "In16.Cu" signal "GND7")
		(2 "B.Cu" signal "BOTTOM")
		(9 "F.Adhes" user "F.Adhesive")
		(11 "B.Adhes" user "B.Adhesive")
		(13 "F.Paste" user "Package Geometry/Pastemask Top")
		(15 "B.Paste" user "Package Geometry/Pastemask Bottom")
		(5 "F.SilkS" user "Ref Des/Silkscreen Top")
		(7 "B.SilkS" user "Ref Des/Silkscreen Bottom")
		(1 "F.Mask" user "Board Geometry/Soldermask Top")
		(3 "B.Mask" user "Board Geometry/Soldermask Bottom")
		(17 "Dwgs.User" user "User.Drawings")
		(19 "Cmts.User" user "User.Comments")
		(21 "Eco1.User" user "User.Eco1")
		(23 "Eco2.User" user "User.Eco2")
		(25 "Edge.Cuts" user "Board Geometry/Outline")
		(27 "Margin" user)
		(31 "F.CrtYd" user "Package Geometry/Place Bound Top")
		(29 "B.CrtYd" user "Package Geometry/Place Bound Bottom")
		(35 "F.Fab" user "Ref Des/Assembly Top")
		(33 "B.Fab" user "Ref Des/Assembly Bottom")
	)
	(footprint ""
		(layer "F.Cu")
		(at 102.09657 -406.03424 180)
		(property "Reference" "R6788"
			(at 0 0 180)
			(layer "F.SilkS")
			(hide yes)
			(effects
				(font
					(size 1.27 1.27)
				)
			)
		)
		(property "Value" ""
			(at 0 0 180)
			(layer "F.Fab")
			(effects
				(font
					(size 1.27 1.27)
				)
			)
		)
		(duplicate_pad_numbers_are_jumpers no)
		(fp_line
			(start 0.32512 0.175006)
			(end -0.32512 0.175006)
			(stroke
				(width 0.1)
				(type default)
			)
			(layer "F.Fab")
		)
		(fp_line
			(start 0.32512 -0.175006)
			(end 0.32512 0.175006)
			(stroke
				(width 0.1)
				(type default)
			)
			(layer "F.Fab")
		)
		(fp_line
			(start -0.32512 0.175006)
			(end -0.32512 -0.175006)
			(stroke
				(width 0.1)
				(type default)
			)
			(layer "F.Fab")
		)
		(fp_line
			(start -0.32512 -0.175006)
			(end 0.32512 -0.175006)
			(stroke
				(width 0.1)
				(type default)
			)
			(layer "F.Fab")
		)
		(pad "1" smd rect
			(at -0.2667 0 180)
			(size 0.3048 0.381)
			(layers "F.Cu" "F.Mask" "F.Paste")
			(net "U12_E2")
		)
		(pad "2" smd rect
			(at 0.2667 0)
			(size 0.3048 0.381)
			(layers "F.Cu" "F.Mask" "F.Paste")
			(net "GND")
		)
	)
	(footprint ""
		(layer "F.Cu")
		(at 305.819048 -47.037498 180)
		(property "Reference" "R3690"
			(at 0 0 180)
			(layer "F.SilkS")
			(hide yes)
			(effects
				(font
					(size 1.27 1.27)
				)
			)
		)
		(property "Value" ""
			(at 0 0 180)
			(layer "F.Fab")
			(effects
				(font
					(size 1.27 1.27)
				)
			)
		)
		(duplicate_pad_numbers_are_jumpers no)
		(fp_line
			(start 0.7874 0.4064)
			(end -0.7874 0.4064)
			(stroke
				(width 0.1524)
				(type default)
			)
			(layer "F.SilkS")
		)
		(fp_line
			(start 0.7874 -0.4064)
			(end 0.7874 0.4064)
			(stroke
				(width 0.1524)
				(type default)
			)
			(layer "F.SilkS")
		)
		(fp_line
			(start -0.7874 0.4064)
			(end -0.7874 -0.4064)
			(stroke
				(width 0.1524)
				(type default)
			)
			(layer "F.SilkS")
		)
		(fp_line
			(start -0.7874 -0.4064)
			(end 0.7874 -0.4064)
			(stroke
				(width 0.1524)
				(type default)
			)
			(layer "F.SilkS")
		)
		(fp_line
			(start 0.67945 0.3048)
			(end 0.120396 0.3048)
			(stroke
				(width 0.1)
				(type default)
			)
			(layer "F.Fab")
		)
		(fp_line
			(start 0.67945 -0.3048)
			(end 0.67945 0.3048)
			(stroke
				(width 0.1)
				(type default)
			)
			(layer "F.Fab")
		)
		(fp_line
			(start 0.12065 -0.2794)
			(end 0.12065 -0.3048)
			(stroke
				(width 0.1)
				(type default)
			)
			(layer "F.Fab")
		)
		(fp_line
			(start 0.12065 -0.3048)
			(end 0.67945 -0.3048)
			(stroke
				(width 0.1)
				(type default)
			)
			(layer "F.Fab")
		)
		(fp_line
			(start 0.120396 0.3048)
			(end 0.120396 0.2794)
			(stroke
				(width 0.1)
				(type default)
			)
			(layer "F.Fab")
		)
		(fp_line
			(start 0.120396 0.2794)
			(end -0.12065 0.2794)
			(stroke
				(width 0.1)
				(type default)
			)
			(layer "F.Fab")
		)
		(fp_line
			(start -0.12065 0.3048)
			(end -0.67945 0.3048)
			(stroke
				(width 0.1)
				(type default)
			)
			(layer "F.Fab")
		)
		(fp_line
			(start -0.12065 0.2794)
			(end -0.12065 0.3048)
			(stroke
				(width 0.1)
				(type default)
			)
			(layer "F.Fab")
		)
		(fp_line
			(start -0.12065 -0.2794)
			(end 0.12065 -0.2794)
			(stroke
				(width 0.1)
				(type default)
			)
			(layer "F.Fab")
		)
		(fp_line
			(start -0.12065 -0.305054)
			(end -0.12065 -0.2794)
			(stroke
				(width 0.1)
				(type default)
			)
			(layer "F.Fab")
		)
		(fp_line
			(start -0.67945 0.3048)
			(end -0.67945 -0.305054)
			(stroke
				(width 0.1)
				(type default)
			)
			(layer "F.Fab")
		)
		(fp_line
			(start -0.67945 -0.305054)
			(end -0.12065 -0.305054)
			(stroke
				(width 0.1)
				(type default)
			)
			(layer "F.Fab")
		)
		(pad "1" smd circle
			(at -0.40005 0 180)
			(size 0 0)
			(layers "F.Cu" "F.Mask" "F.Paste")
			(net "ADC128_VREF")
		)
		(pad "2" smd circle
			(at 0.40005 0 180)
			(size 0 0)
			(layers "F.Cu" "F.Mask" "F.Paste")
			(net "GND")
		)
	)
	(footprint ""
		(layer "F.Cu")
		(at 93.29801 -53.685694)
		(property "Reference" "PC2140"
			(at 0 0 0)
			(layer "F.SilkS")
			(hide yes)
			(effects
				(font
					(size 1.27 1.27)
				)
			)
		)
		(property "Value" ""
			(at 0 0 0)
			(layer "F.Fab")
			(effects
				(font
					(size 1.27 1.27)
				)
			)
		)
		(duplicate_pad_numbers_are_jumpers no)
		(fp_line
			(start -0.7874 -0.4064)
			(end 0.7874 -0.4064)
			(stroke
				(width 0.1524)
				(type default)
			)
			(layer "F.SilkS")
		)
		(fp_line
			(start -0.7874 0.4064)
			(end -0.7874 -0.4064)
			(stroke
				(width 0.1524)
				(type default)
			)
			(layer "F.SilkS")
		)
		(fp_line
			(start 0.7874 -0.4064)
			(end 0.7874 0.4064)
			(stroke
				(width 0.1524)
				(type default)
			)
			(layer "F.SilkS")
		)
		(fp_line
			(start 0.7874 0.4064)
			(end -0.7874 0.4064)
			(stroke
				(width 0.1524)
				(type default)
			)
			(layer "F.SilkS")
		)
		(fp_line
			(start -0.67945 -0.305054)
			(end -0.12065 -0.305054)
			(stroke
				(width 0.1)
				(type default)
			)
			(layer "F.Fab")
		)
		(fp_line
			(start -0.67945 0.3048)
			(end -0.67945 -0.305054)
			(stroke
				(width 0.1)
				(type default)
			)
			(layer "F.Fab")
		)
		(fp_line
			(start -0.12065 -0.305054)
			(end -0.12065 -0.2794)
			(stroke
				(width 0.1)
				(type default)
			)
			(layer "F.Fab")
		)
		(fp_line
			(start -0.12065 -0.2794)
			(end 0.12065 -0.2794)
			(stroke
				(width 0.1)
				(type default)
			)
			(layer "F.Fab")
		)
		(fp_line
			(start -0.12065 0.2794)
			(end -0.12065 0.3048)
			(stroke
				(width 0.1)
				(type default)
			)
			(layer "F.Fab")
		)
		(fp_line
			(start -0.12065 0.3048)
			(end -0.67945 0.3048)
			(stroke
				(width 0.1)
				(type default)
			)
			(layer "F.Fab")
		)
		(fp_line
			(start 0.120396 0.2794)
			(end -0.12065 0.2794)
			(stroke
				(width 0.1)
				(type default)
			)
			(layer "F.Fab")
		)
		(fp_line
			(start 0.120396 0.3048)
			(end 0.120396 0.2794)
			(stroke
				(width 0.1)
				(type default)
			)
			(layer "F.Fab")
		)
		(fp_line
			(start 0.12065 -0.3048)
			(end 0.67945 -0.3048)
			(stroke
				(width 0.1)
				(type default)
			)
			(layer "F.Fab")
		)
		(fp_line
			(start 0.12065 -0.2794)
			(end 0.12065 -0.3048)
			(stroke
				(width 0.1)
				(type default)
			)
			(layer "F.Fab")
		)
		(fp_line
			(start 0.67945 -0.3048)
			(end 0.67945 0.3048)
			(stroke
				(width 0.1)
				(type default)
			)
			(layer "F.Fab")
		)
		(fp_line
			(start 0.67945 0.3048)
			(end 0.120396 0.3048)
			(stroke
				(width 0.1)
				(type default)
			)
			(layer "F.Fab")
		)
		(pad "1" smd circle
			(at -0.40005 0)
			(size 0 0)
			(layers "F.Cu" "F.Mask" "F.Paste")
			(net "P3V3_AUX")
		)
		(pad "2" smd circle
			(at 0.40005 0)
			(size 0 0)
			(layers "F.Cu" "F.Mask" "F.Paste")
			(net "GND")
		)
	)
)
